(kicad_pcb
	(version 20260206)
	(generator "pcbnew")
	(generator_version "10.0")
	(general
		(thickness 1.6)
		(legacy_teardrops no)
	)
	(paper "A4")
	(title_block
		(title "01162023_DA0F0TEBIF0_F0T_Expander_BD_F_brd_V02_OCP.brd")
		(comment 1 "Grand Teton / footprints 9356-9363 of 9728")
	)
	(layers
		(0 "F.Cu" signal "TOP")
		(4 "In1.Cu" signal "GND")
		(6 "In2.Cu" signal "VCC")
		(8 "In3.Cu" signal "VCC1")
		(10 "In4.Cu" signal "GND1")
		(12 "In5.Cu" signal "IN1")
		(14 "In6.Cu" signal "GND2")
		(16 "In7.Cu" signal "IN2")
		(18 "In8.Cu" signal "GND3")
		(20 "In9.Cu" signal "IN3")
		(22 "In10.Cu" signal "GND4")
		(24 "In11.Cu" signal "IN4")
		(26 "In12.Cu" signal "GND5")
		(28 "In13.Cu" signal "IN5")
		(30 "In14.Cu" signal "GND6")
		(32 "In15.Cu" signal "IN6")
		(34 "In16.Cu" signal "GND7")
		(2 "B.Cu" signal "BOTTOM")
		(9 "F.Adhes" user "F.Adhesive")
		(11 "B.Adhes" user "B.Adhesive")
		(13 "F.Paste" user "Package Geometry/Pastemask Top")
		(15 "B.Paste" user "Package Geometry/Pastemask Bottom")
		(5 "F.SilkS" user "Ref Des/Silkscreen Top")
		(7 "B.SilkS" user "Ref Des/Silkscreen Bottom")
		(1 "F.Mask" user "Board Geometry/Soldermask Top")
		(3 "B.Mask" user "Board Geometry/Soldermask Bottom")
		(17 "Dwgs.User" user "User.Drawings")
		(19 "Cmts.User" user "User.Comments")
		(21 "Eco1.User" user "User.Eco1")
		(23 "Eco2.User" user "User.Eco2")
		(25 "Edge.Cuts" user "Board Geometry/Outline")
		(27 "Margin" user)
		(31 "F.CrtYd" user "Package Geometry/Place Bound Top")
		(29 "B.CrtYd" user "Package Geometry/Place Bound Bottom")
		(35 "F.Fab" user "Ref Des/Assembly Top")
		(33 "B.Fab" user "Ref Des/Assembly Bottom")
	)
	(footprint ""
		(layer "B.Cu")
		(at 341.619586 -282.040584 90)
		(property "Reference" "PR150"
			(at 0 0 90)
			(layer "B.SilkS")
			(hide yes)
			(effects
				(font
					(size 1.27 1.27)
				)
				(justify mirror)
			)
		)
		(property "Value" ""
			(at 0 0 90)
			(layer "B.Fab")
			(effects
				(font
					(size 1.27 1.27)
				)
				(justify mirror)
			)
		)
		(duplicate_pad_numbers_are_jumpers no)
		(fp_line
			(start 0.7874 -0.4064)
			(end -0.7874 -0.4064)
			(stroke
				(width 0.1524)
				(type default)
			)
			(layer "B.SilkS")
		)
		(fp_line
			(start -0.7874 -0.4064)
			(end -0.7874 0.4064)
			(stroke
				(width 0.1524)
				(type default)
			)
			(layer "B.SilkS")
		)
		(fp_line
			(start 0.7874 0.4064)
			(end 0.7874 -0.4064)
			(stroke
				(width 0.1524)
				(type default)
			)
			(layer "B.SilkS")
		)
		(fp_line
			(start -0.7874 0.4064)
			(end 0.7874 0.4064)
			(stroke
				(width 0.1524)
				(type default)
			)
			(layer "B.SilkS")
		)
		(fp_line
			(start 0.67945 -0.305054)
			(end 0.12065 -0.305054)
			(stroke
				(width 0.1)
				(type default)
			)
			(layer "B.Fab")
		)
		(fp_line
			(start 0.12065 -0.305054)
			(end 0.12065 -0.2794)
			(stroke
				(width 0.1)
				(type default)
			)
			(layer "B.Fab")
		)
		(fp_line
			(start -0.12065 -0.3048)
			(end -0.67945 -0.3048)
			(stroke
				(width 0.1)
				(type default)
			)
			(layer "B.Fab")
		)
		(fp_line
			(start -0.67945 -0.3048)
			(end -0.67945 0.3048)
			(stroke
				(width 0.1)
				(type default)
			)
			(layer "B.Fab")
		)
		(fp_line
			(start 0.12065 -0.2794)
			(end -0.12065 -0.2794)
			(stroke
				(width 0.1)
				(type default)
			)
			(layer "B.Fab")
		)
		(fp_line
			(start -0.12065 -0.2794)
			(end -0.12065 -0.3048)
			(stroke
				(width 0.1)
				(type default)
			)
			(layer "B.Fab")
		)
		(fp_line
			(start 0.12065 0.2794)
			(end 0.12065 0.3048)
			(stroke
				(width 0.1)
				(type default)
			)
			(layer "B.Fab")
		)
		(fp_line
			(start -0.120396 0.2794)
			(end 0.12065 0.2794)
			(stroke
				(width 0.1)
				(type default)
			)
			(layer "B.Fab")
		)
		(fp_line
			(start 0.67945 0.3048)
			(end 0.67945 -0.305054)
			(stroke
				(width 0.1)
				(type default)
			)
			(layer "B.Fab")
		)
		(fp_line
			(start 0.12065 0.3048)
			(end 0.67945 0.3048)
			(stroke
				(width 0.1)
				(type default)
			)
			(layer "B.Fab")
		)
		(fp_line
			(start -0.120396 0.3048)
			(end -0.120396 0.2794)
			(stroke
				(width 0.1)
				(type default)
			)
			(layer "B.Fab")
		)
		(fp_line
			(start -0.67945 0.3048)
			(end -0.120396 0.3048)
			(stroke
				(width 0.1)
				(type default)
			)
			(layer "B.Fab")
		)
		(pad "1" smd circle
			(at 0.40005 0 270)
			(size 0 0)
			(layers "B.Cu" "B.Mask" "B.Paste")
			(net "SW_P0V8_PEX2_VOS1")
		)
		(pad "2" smd circle
			(at -0.40005 0 270)
			(size 0 0)
			(layers "B.Cu" "B.Mask" "B.Paste")
			(net "P0V8_PEX2")
		)
	)
	(footprint ""
		(layer "B.Cu")
		(at 372.759224 -226.535996 -90)
		(property "Reference" "R3506"
			(at 0 0 90)
			(layer "B.SilkS")
			(hide yes)
			(effects
				(font
					(size 1.27 1.27)
				)
				(justify mirror)
			)
		)
		(property "Value" ""
			(at 0 0 90)
			(layer "B.Fab")
			(effects
				(font
					(size 1.27 1.27)
				)
				(justify mirror)
			)
		)
		(duplicate_pad_numbers_are_jumpers no)
		(fp_line
			(start -0.7874 0.4064)
			(end 0.7874 0.4064)
			(stroke
				(width 0.1524)
				(type default)
			)
			(layer "B.SilkS")
		)
		(fp_line
			(start 0.7874 0.4064)
			(end 0.7874 -0.4064)
			(stroke
				(width 0.1524)
				(type default)
			)
			(layer "B.SilkS")
		)
		(fp_line
			(start -0.7874 -0.4064)
			(end -0.7874 0.4064)
			(stroke
				(width 0.1524)
				(type default)
			)
			(layer "B.SilkS")
		)
		(fp_line
			(start 0.7874 -0.4064)
			(end -0.7874 -0.4064)
			(stroke
				(width 0.1524)
				(type default)
			)
			(layer "B.SilkS")
		)
		(fp_line
			(start -0.67945 0.3048)
			(end -0.120396 0.3048)
			(stroke
				(width 0.1)
				(type default)
			)
			(layer "B.Fab")
		)
		(fp_line
			(start -0.120396 0.3048)
			(end -0.120396 0.2794)
			(stroke
				(width 0.1)
				(type default)
			)
			(layer "B.Fab")
		)
		(fp_line
			(start 0.12065 0.3048)
			(end 0.67945 0.3048)
			(stroke
				(width 0.1)
				(type default)
			)
			(layer "B.Fab")
		)
		(fp_line
			(start 0.67945 0.3048)
			(end 0.67945 -0.305054)
			(stroke
				(width 0.1)
				(type default)
			)
			(layer "B.Fab")
		)
		(fp_line
			(start -0.120396 0.2794)
			(end 0.12065 0.2794)
			(stroke
				(width 0.1)
				(type default)
			)
			(layer "B.Fab")
		)
		(fp_line
			(start 0.12065 0.2794)
			(end 0.12065 0.3048)
			(stroke
				(width 0.1)
				(type default)
			)
			(layer "B.Fab")
		)
		(fp_line
			(start -0.12065 -0.2794)
			(end -0.12065 -0.3048)
			(stroke
				(width 0.1)
				(type default)
			)
			(layer "B.Fab")
		)
		(fp_line
			(start 0.12065 -0.2794)
			(end -0.12065 -0.2794)
			(stroke
				(width 0.1)
				(type default)
			)
			(layer "B.Fab")
		)
		(fp_line
			(start -0.67945 -0.3048)
			(end -0.67945 0.3048)
			(stroke
				(width 0.1)
				(type default)
			)
			(layer "B.Fab")
		)
		(fp_line
			(start -0.12065 -0.3048)
			(end -0.67945 -0.3048)
			(stroke
				(width 0.1)
				(type default)
			)
			(layer "B.Fab")
		)
		(fp_line
			(start 0.12065 -0.305054)
			(end 0.12065 -0.2794)
			(stroke
				(width 0.1)
				(type default)
			)
			(layer "B.Fab")
		)
		(fp_line
			(start 0.67945 -0.305054)
			(end 0.12065 -0.305054)
			(stroke
				(width 0.1)
				(type default)
			)
			(layer "B.Fab")
		)
		(pad "1" smd circle
			(at 0.40005 0 90)
			(size 0 0)
			(layers "B.Cu" "B.Mask" "B.Paste")
			(net "P1V8_PEX")
		)
		(pad "2" smd circle
			(at -0.40005 0 90)
			(size 0 0)
			(layers "B.Cu" "B.Mask" "B.Paste")
			(net "SPI_PEX3_CS_MUX_R_N")
		)
	)
	(footprint ""
		(layer "B.Cu")
		(at 347.66631 -256.226564 90)
		(property "Reference" "PR147"
			(at 0 0 90)
			(layer "B.SilkS")
			(hide yes)
			(effects
				(font
					(size 1.27 1.27)
				)
				(justify mirror)
			)
		)
		(property "Value" ""
			(at 0 0 90)
			(layer "B.Fab")
			(effects
				(font
					(size 1.27 1.27)
				)
				(justify mirror)
			)
		)
		(duplicate_pad_numbers_are_jumpers no)
		(fp_line
			(start 0.7874 -0.4064)
			(end -0.7874 -0.4064)
			(stroke
				(width 0.1524)
				(type default)
			)
			(layer "B.SilkS")
		)
		(fp_line
			(start -0.7874 -0.4064)
			(end -0.7874 0.4064)
			(stroke
				(width 0.1524)
				(type default)
			)
			(layer "B.SilkS")
		)
		(fp_line
			(start 0.7874 0.4064)
			(end 0.7874 -0.4064)
			(stroke
				(width 0.1524)
				(type default)
			)
			(layer "B.SilkS")
		)
		(fp_line
			(start -0.7874 0.4064)
			(end 0.7874 0.4064)
			(stroke
				(width 0.1524)
				(type default)
			)
			(layer "B.SilkS")
		)
		(fp_line
			(start 0.67945 -0.305054)
			(end 0.12065 -0.305054)
			(stroke
				(width 0.1)
				(type default)
			)
			(layer "B.Fab")
		)
		(fp_line
			(start 0.12065 -0.305054)
			(end 0.12065 -0.2794)
			(stroke
				(width 0.1)
				(type default)
			)
			(layer "B.Fab")
		)
		(fp_line
			(start -0.12065 -0.3048)
			(end -0.67945 -0.3048)
			(stroke
				(width 0.1)
				(type default)
			)
			(layer "B.Fab")
		)
		(fp_line
			(start -0.67945 -0.3048)
			(end -0.67945 0.3048)
			(stroke
				(width 0.1)
				(type default)
			)
			(layer "B.Fab")
		)
		(fp_line
			(start 0.12065 -0.2794)
			(end -0.12065 -0.2794)
			(stroke
				(width 0.1)
				(type default)
			)
			(layer "B.Fab")
		)
		(fp_line
			(start -0.12065 -0.2794)
			(end -0.12065 -0.3048)
			(stroke
				(width 0.1)
				(type default)
			)
			(layer "B.Fab")
		)
		(fp_line
			(start 0.12065 0.2794)
			(end 0.12065 0.3048)
			(stroke
				(width 0.1)
				(type default)
			)
			(layer "B.Fab")
		)
		(fp_line
			(start -0.120396 0.2794)
			(end 0.12065 0.2794)
			(stroke
				(width 0.1)
				(type default)
			)
			(layer "B.Fab")
		)
		(fp_line
			(start 0.67945 0.3048)
			(end 0.67945 -0.305054)
			(stroke
				(width 0.1)
				(type default)
			)
			(layer "B.Fab")
		)
		(fp_line
			(start 0.12065 0.3048)
			(end 0.67945 0.3048)
			(stroke
				(width 0.1)
				(type default)
			)
			(layer "B.Fab")
		)
		(fp_line
			(start -0.120396 0.3048)
			(end -0.120396 0.2794)
			(stroke
				(width 0.1)
				(type default)
			)
			(layer "B.Fab")
		)
		(fp_line
			(start -0.67945 0.3048)
			(end -0.120396 0.3048)
			(stroke
				(width 0.1)
				(type default)
			)
			(layer "B.Fab")
		)
		(pad "1" smd circle
			(at 0.40005 0 270)
			(size 0 0)
			(layers "B.Cu" "B.Mask" "B.Paste")
			(net "P0V8_PEX2_VINSEN")
		)
		(pad "2" smd circle
			(at -0.40005 0 270)
			(size 0 0)
			(layers "B.Cu" "B.Mask" "B.Paste")
			(net "GND")
		)
	)
	(footprint ""
		(layer "B.Cu")
		(at 177.423826 -191.381634)
		(property "Reference" "R1036"
			(at 0 0 0)
			(layer "B.SilkS")
			(hide yes)
			(effects
				(font
					(size 1.27 1.27)
				)
				(justify mirror)
			)
		)
		(property "Value" ""
			(at 0 0 0)
			(layer "B.Fab")
			(effects
				(font
					(size 1.27 1.27)
				)
				(justify mirror)
			)
		)
		(duplicate_pad_numbers_are_jumpers no)
		(fp_line
			(start -0.7874 -0.4064)
			(end -0.7874 0.4064)
			(stroke
				(width 0.1524)
				(type default)
			)
			(layer "B.SilkS")
		)
		(fp_line
			(start -0.7874 0.4064)
			(end 0.7874 0.4064)
			(stroke
				(width 0.1524)
				(type default)
			)
			(layer "B.SilkS")
		)
		(fp_line
			(start 0.7874 -0.4064)
			(end -0.7874 -0.4064)
			(stroke
				(width 0.1524)
				(type default)
			)
			(layer "B.SilkS")
		)
		(fp_line
			(start 0.7874 0.4064)
			(end 0.7874 -0.4064)
			(stroke
				(width 0.1524)
				(type default)
			)
			(layer "B.SilkS")
		)
		(fp_line
			(start -0.67945 -0.3048)
			(end -0.67945 0.3048)
			(stroke
				(width 0.1)
				(type default)
			)
			(layer "B.Fab")
		)
		(fp_line
			(start -0.67945 0.3048)
			(end -0.120396 0.3048)
			(stroke
				(width 0.1)
				(type default)
			)
			(layer "B.Fab")
		)
		(fp_line
			(start -0.12065 -0.3048)
			(end -0.67945 -0.3048)
			(stroke
				(width 0.1)
				(type default)
			)
			(layer "B.Fab")
		)
		(fp_line
			(start -0.12065 -0.2794)
			(end -0.12065 -0.3048)
			(stroke
				(width 0.1)
				(type default)
			)
			(layer "B.Fab")
		)
		(fp_line
			(start -0.120396 0.2794)
			(end 0.12065 0.2794)
			(stroke
				(width 0.1)
				(type default)
			)
			(layer "B.Fab")
		)
		(fp_line
			(start -0.120396 0.3048)
			(end -0.120396 0.2794)
			(stroke
				(width 0.1)
				(type default)
			)
			(layer "B.Fab")
		)
		(fp_line
			(start 0.12065 -0.305054)
			(end 0.12065 -0.2794)
			(stroke
				(width 0.1)
				(type default)
			)
			(layer "B.Fab")
		)
		(fp_line
			(start 0.12065 -0.2794)
			(end -0.12065 -0.2794)
			(stroke
				(width 0.1)
				(type default)
			)
			(layer "B.Fab")
		)
		(fp_line
			(start 0.12065 0.2794)
			(end 0.12065 0.3048)
			(stroke
				(width 0.1)
				(type default)
			)
			(layer "B.Fab")
		)
		(fp_line
			(start 0.12065 0.3048)
			(end 0.67945 0.3048)
			(stroke
				(width 0.1)
				(type default)
			)
			(layer "B.Fab")
		)
		(fp_line
			(start 0.67945 -0.305054)
			(end 0.12065 -0.305054)
			(stroke
				(width 0.1)
				(type default)
			)
			(layer "B.Fab")
		)
		(fp_line
			(start 0.67945 0.3048)
			(end 0.67945 -0.305054)
			(stroke
				(width 0.1)
				(type default)
			)
			(layer "B.Fab")
		)
		(pad "1" smd circle
			(at 0.40005 0 180)
			(size 0 0)
			(layers "B.Cu" "B.Mask" "B.Paste")
			(net "GND")
		)
		(pad "2" smd circle
			(at -0.40005 0 180)
			(size 0 0)
			(layers "B.Cu" "B.Mask" "B.Paste")
			(net "SPI_BIC1_MISO_LS01_DIR4")
		)
	)
	(footprint ""
		(layer "B.Cu")
		(at 168.150032 -292.099746 90)
		(property "Reference" "C1434"
			(at 0 0 90)
			(layer "B.SilkS")
			(hide yes)
			(effects
				(font
					(size 1.27 1.27)
				)
				(justify mirror)
			)
		)
		(property "Value" ""
			(at 0 0 90)
			(layer "B.Fab")
			(effects
				(font
					(size 1.27 1.27)
				)
				(justify mirror)
			)
		)
		(duplicate_pad_numbers_are_jumpers no)
		(fp_line
			(start 0.299974 -0.150114)
			(end -0.299974 -0.150114)
			(stroke
				(width 0.1)
				(type default)
			)
			(layer "B.Fab")
		)
		(fp_line
			(start -0.299974 -0.150114)
			(end -0.299974 0.150114)
			(stroke
				(width 0.1)
				(type default)
			)
			(layer "B.Fab")
		)
		(fp_line
			(start 0.299974 0.150114)
			(end 0.299974 -0.150114)
			(stroke
				(width 0.1)
				(type default)
			)
			(layer "B.Fab")
		)
		(fp_line
			(start -0.299974 0.150114)
			(end 0.299974 0.150114)
			(stroke
				(width 0.1)
				(type default)
			)
			(layer "B.Fab")
		)
		(pad "1" smd rect
			(at 0.2667 0 270)
			(size 0.3048 0.381)
			(layers "B.Cu" "B.Mask" "B.Paste")
			(net "P0V8_SERDES_VDDA_PEX1")
		)
		(pad "2" smd rect
			(at -0.2667 0 270)
			(size 0.3048 0.381)
			(layers "B.Cu" "B.Mask" "B.Paste")
			(net "GND")
		)
	)
	(footprint ""
		(layer "B.Cu")
		(at 65.851278 -305.399948 -90)
		(property "Reference" "C2956"
			(at 0 0 90)
			(layer "B.SilkS")
			(hide yes)
			(effects
				(font
					(size 1.27 1.27)
				)
				(justify mirror)
			)
		)
		(property "Value" ""
			(at 0 0 90)
			(layer "B.Fab")
			(effects
				(font
					(size 1.27 1.27)
				)
				(justify mirror)
			)
		)
		(duplicate_pad_numbers_are_jumpers no)
		(fp_line
			(start -0.299974 0.150114)
			(end 0.299974 0.150114)
			(stroke
				(width 0.1)
				(type default)
			)
			(layer "B.Fab")
		)
		(fp_line
			(start 0.299974 0.150114)
			(end 0.299974 -0.150114)
			(stroke
				(width 0.1)
				(type default)
			)
			(layer "B.Fab")
		)
		(fp_line
			(start -0.299974 -0.150114)
			(end -0.299974 0.150114)
			(stroke
				(width 0.1)
				(type default)
			)
			(layer "B.Fab")
		)
		(fp_line
			(start 0.299974 -0.150114)
			(end -0.299974 -0.150114)
			(stroke
				(width 0.1)
				(type default)
			)
			(layer "B.Fab")
		)
		(pad "1" smd rect
			(at 0.2667 0 90)
			(size 0.3048 0.381)
			(layers "B.Cu" "B.Mask" "B.Paste")
			(net "P1V25_SERDES_VDDPLL_PEX0")
		)
		(pad "2" smd rect
			(at -0.2667 0 90)
			(size 0.3048 0.381)
			(layers "B.Cu" "B.Mask" "B.Paste")
			(net "GND")
		)
	)
	(footprint ""
		(layer "B.Cu")
		(at 278.064214 -145.284952 180)
		(property "Reference" "C911"
			(at 0 0 0)
			(layer "B.SilkS")
			(hide yes)
			(effects
				(font
					(size 1.27 1.27)
				)
				(justify mirror)
			)
		)
		(property "Value" ""
			(at 0 0 0)
			(layer "B.Fab")
			(effects
				(font
					(size 1.27 1.27)
				)
				(justify mirror)
			)
		)
		(duplicate_pad_numbers_are_jumpers no)
		(fp_line
			(start 0.299974 0.150114)
			(end 0.299974 -0.150114)
			(stroke
				(width 0.1)
				(type default)
			)
			(layer "B.Fab")
		)
		(fp_line
			(start 0.299974 -0.150114)
			(end -0.299974 -0.150114)
			(stroke
				(width 0.1)
				(type default)
			)
			(layer "B.Fab")
		)
		(fp_line
			(start -0.299974 0.150114)
			(end 0.299974 0.150114)
			(stroke
				(width 0.1)
				(type default)
			)
			(layer "B.Fab")
		)
		(fp_line
			(start -0.299974 -0.150114)
			(end -0.299974 0.150114)
			(stroke
				(width 0.1)
				(type default)
			)
			(layer "B.Fab")
		)
		(pad "1" smd rect
			(at 0.2667 0)
			(size 0.3048 0.381)
			(layers "B.Cu" "B.Mask" "B.Paste")
			(net "P12V_NIC4")
		)
		(pad "2" smd rect
			(at -0.2667 0)
			(size 0.3048 0.381)
			(layers "B.Cu" "B.Mask" "B.Paste")
			(net "GND")
		)
	)
	(footprint ""
		(layer "B.Cu")
		(at 46.355 -297.32478)
		(property "Reference" "C3028"
			(at 0 0 0)
			(layer "B.SilkS")
			(hide yes)
			(effects
				(font
					(size 1.27 1.27)
				)
				(justify mirror)
			)
		)
		(property "Value" ""
			(at 0 0 0)
			(layer "B.Fab")
			(effects
				(font
					(size 1.27 1.27)
				)
				(justify mirror)
			)
		)
		(duplicate_pad_numbers_are_jumpers no)
		(fp_line
			(start -0.299974 -0.150114)
			(end -0.299974 0.150114)
			(stroke
				(width 0.1)
				(type default)
			)
			(layer "B.Fab")
		)
		(fp_line
			(start -0.299974 0.150114)
			(end 0.299974 0.150114)
			(stroke
				(width 0.1)
				(type default)
			)
			(layer "B.Fab")
		)
		(fp_line
			(start 0.299974 -0.150114)
			(end -0.299974 -0.150114)
			(stroke
				(width 0.1)
				(type default)
			)
			(layer "B.Fab")
		)
		(fp_line
			(start 0.299974 0.150114)
			(end 0.299974 -0.150114)
			(stroke
				(width 0.1)
				(type default)
			)
			(layer "B.Fab")
		)
		(pad "1" smd rect
			(at 0.2667 0 180)
			(size 0.3048 0.381)
			(layers "B.Cu" "B.Mask" "B.Paste")
			(net "PCEPLL2_VDDA18_PEX0")
		)
		(pad "2" smd rect
			(at -0.2667 0 180)
			(size 0.3048 0.381)
			(layers "B.Cu" "B.Mask" "B.Paste")
			(net "GND")
		)
	)
)
